(kicad_pcb
	(version 20260206)
	(generator "pcbnew")
	(generator_version "10.0")
	(general
		(thickness 1.6)
		(legacy_teardrops no)
	)
	(paper "A4")
	(title_block
		(title "Bryce Canyon_F.DPB_16315-1-OCP.brd")
		(comment 1 "Bryce Canyon / footprints 1917-1924 of 2223")
	)
	(layers
		(0 "F.Cu" signal "TOP")
		(4 "In1.Cu" signal "L2GND")
		(6 "In2.Cu" signal "L3")
		(8 "In3.Cu" signal "L4GND")
		(10 "In4.Cu" signal "L5")
		(12 "In5.Cu" signal "L6VCC")
		(14 "In6.Cu" signal "L7VCC")
		(16 "In7.Cu" signal "L8")
		(18 "In8.Cu" signal "L9GND")
		(20 "In9.Cu" signal "L10")
		(22 "In10.Cu" signal "L11GND")
		(2 "B.Cu" signal "BOTTOM")
		(9 "F.Adhes" user "F.Adhesive")
		(11 "B.Adhes" user "B.Adhesive")
		(13 "F.Paste" user "Package Geometry/Pastemask Top")
		(15 "B.Paste" user "Package Geometry/Pastemask Bottom")
		(5 "F.SilkS" user "Ref Des/Silkscreen Top")
		(7 "B.SilkS" user "Ref Des/Silkscreen Bottom")
		(1 "F.Mask" user "Board Geometry/Soldermask Top")
		(3 "B.Mask" user "Board Geometry/Soldermask Bottom")
		(17 "Dwgs.User" user "User.Drawings")
		(19 "Cmts.User" user "User.Comments")
		(21 "Eco1.User" user "User.Eco1")
		(23 "Eco2.User" user "User.Eco2")
		(25 "Edge.Cuts" user "Board Geometry/Outline")
		(27 "Margin" user)
		(31 "F.CrtYd" user "Package Geometry/Place Bound Top")
		(29 "B.CrtYd" user "Package Geometry/Place Bound Bottom")
		(35 "F.Fab" user "Ref Des/Assembly Top")
		(33 "B.Fab" user "Ref Des/Assembly Bottom")
	)
	(footprint ""
		(layer "F.Cu")
		(at 176.657 -64.683894 90)
		(property "Reference" "R798"
			(at 0 0 90)
			(layer "F.SilkS")
			(hide yes)
			(effects
				(font
					(size 1.27 1.27)
				)
			)
		)
		(property "Value" "2R6F-GP"
			(at -0.0508 -4.8514 90)
			(unlocked yes)
			(layer "F.Fab")
			(hide yes)
			(effects
				(font
					(size 1.016 1.016)
					(thickness 0.1524)
				)
			)
		)
		(property "Device Type" "R1206H26"
			(at 0 -6.3754 90)
			(unlocked yes)
			(layer "F.Fab")
			(hide yes)
			(effects
				(font
					(size 1.016 1.016)
					(thickness 0.1524)
				)
			)
		)
		(duplicate_pad_numbers_are_jumpers no)
		(fp_line
			(start 1.016 -2.2352)
			(end 1.016 2.2352)
			(stroke
				(width 0.1524)
				(type default)
			)
			(layer "F.SilkS")
		)
		(fp_line
			(start -1.016 -2.2352)
			(end 1.016 -2.2352)
			(stroke
				(width 0.1524)
				(type default)
			)
			(layer "F.SilkS")
		)
		(fp_line
			(start 1.016 2.2352)
			(end -1.016 2.2352)
			(stroke
				(width 0.1524)
				(type default)
			)
			(layer "F.SilkS")
		)
		(fp_line
			(start -1.016 2.2352)
			(end -1.016 -2.2352)
			(stroke
				(width 0.1524)
				(type default)
			)
			(layer "F.SilkS")
		)
		(fp_rect
			(start -1.0922 2.3114)
			(end 1.0922 -2.3114)
			(stroke
				(width 0)
				(type default)
			)
			(fill no)
			(layer "F.CrtYd")
		)
		(fp_poly
			(pts
				(xy -1.0922 -2.3114) (xy 1.0922 -2.3114) (xy 1.0922 2.3114) (xy -1.0922 2.3114)
			)
			(stroke
				(width 0)
				(type default)
			)
			(fill no)
			(layer "F.Fab")
		)
		(pad "1" smd rect
			(at 0 -1.397 90)
			(size 1.651 1.27)
			(layers "F.Cu" "F.Mask" "F.Paste")
			(net "P12V_HDD29")
		)
		(pad "2" smd rect
			(at 0 1.397 90)
			(size 1.651 1.27)
			(layers "F.Cu" "F.Mask" "F.Paste")
			(net "12V_PRE_29")
		)
	)
	(footprint ""
		(layer "F.Cu")
		(at 413.318452 -61.102494 -90)
		(property "Reference" "C474"
			(at 0 0 270)
			(layer "F.SilkS")
			(hide yes)
			(effects
				(font
					(size 1.27 1.27)
				)
			)
		)
		(property "Value" "SCD01U50V2KX-1GP"
			(at 1.1811 -2.7051 270)
			(unlocked yes)
			(layer "F.Fab")
			(hide yes)
			(effects
				(font
					(size 1.016 1.016)
					(thickness 0.1524)
				)
			)
		)
		(property "Device Type" "C402H22"
			(at 1.1811 -4.2291 270)
			(unlocked yes)
			(layer "F.Fab")
			(hide yes)
			(effects
				(font
					(size 1.016 1.016)
					(thickness 0.1524)
				)
			)
		)
		(duplicate_pad_numbers_are_jumpers no)
		(fp_rect
			(start -0.4318 0.9525)
			(end 0.4318 -0.9525)
			(stroke
				(width 0)
				(type default)
			)
			(fill no)
			(layer "F.CrtYd")
		)
		(fp_rect
			(start -0.4318 0.9525)
			(end 0.4318 -0.9525)
			(stroke
				(width 0)
				(type default)
			)
			(fill no)
			(layer "F.Fab")
		)
		(pad "1" smd custom
			(at 0 -0.4445 270)
			(size 0.1524 0.1524)
			(layers "F.Cu" "F.Mask" "F.Paste")
			(net "HDD_PRSNT_33")
			(options
				(clearance outline)
				(anchor circle)
			)
			(primitives
				(gr_poly
					(pts
						(arc
							(start 0.3048 -0.2032)
							(mid 0.275042 -0.275042)
							(end 0.2032 -0.3048)
						)
						(arc
							(start -0.2032 -0.3048)
							(mid -0.275042 -0.275042)
							(end -0.3048 -0.2032)
						)
						(arc
							(start -0.3048 0.2032)
							(mid -0.275042 0.275042)
							(end -0.2032 0.3048)
						)
						(arc
							(start 0.2032 0.3048)
							(mid 0.275042 0.275042)
							(end 0.3048 0.2032)
						)
					)
					(width 0)
					(fill yes)
				)
			)
		)
		(pad "2" smd custom
			(at 0 0.4445 270)
			(size 0.1524 0.1524)
			(layers "F.Cu" "F.Mask" "F.Paste")
			(net "GND")
			(options
				(clearance outline)
				(anchor circle)
			)
			(primitives
				(gr_poly
					(pts
						(arc
							(start 0.3048 -0.2032)
							(mid 0.275042 -0.275042)
							(end 0.2032 -0.3048)
						)
						(arc
							(start -0.2032 -0.3048)
							(mid -0.275042 -0.275042)
							(end -0.3048 -0.2032)
						)
						(arc
							(start -0.3048 0.2032)
							(mid -0.275042 0.275042)
							(end -0.2032 0.3048)
						)
						(arc
							(start 0.2032 0.3048)
							(mid 0.275042 0.275042)
							(end 0.3048 0.2032)
						)
					)
					(width 0)
					(fill yes)
				)
			)
		)
	)
	(footprint ""
		(layer "F.Cu")
		(at 141.042898 -59.857894)
		(property "Reference" "Q170"
			(at 0 0 0)
			(layer "F.SilkS")
			(hide yes)
			(effects
				(font
					(size 1.27 1.27)
				)
			)
		)
		(property "Value" "AO4407AL-GP"
			(at -3.707384 -1.5367 0)
			(unlocked yes)
			(layer "F.Fab")
			(hide yes)
			(effects
				(font
					(size 1.016 1.016)
					(thickness 0.1524)
				)
			)
		)
		(property "Device Type" "SOIC8H69"
			(at -3.707384 -3.0607 0)
			(unlocked yes)
			(layer "F.Fab")
			(hide yes)
			(effects
				(font
					(size 1.016 1.016)
					(thickness 0.1524)
				)
			)
		)
		(duplicate_pad_numbers_are_jumpers no)
		(fp_line
			(start -2.7432 -1.4224)
			(end -2.7432 1.4224)
			(stroke
				(width 0.1524)
				(type default)
			)
			(layer "F.SilkS")
		)
		(fp_line
			(start -2.7432 1.4224)
			(end -2.6416 1.4224)
			(stroke
				(width 0.1524)
				(type default)
			)
			(layer "F.SilkS")
		)
		(fp_line
			(start -2.7432 1.4224)
			(end 2.1336 1.4224)
			(stroke
				(width 0.1524)
				(type default)
			)
			(layer "F.SilkS")
		)
		(fp_line
			(start -2.7178 -0.508)
			(end -2.1844 -0.0508)
			(stroke
				(width 0.1524)
				(type default)
			)
			(layer "F.SilkS")
		)
		(fp_line
			(start -2.6289 3.4417)
			(end -2.6289 1.4732)
			(stroke
				(width 0.381)
				(type default)
			)
			(layer "F.SilkS")
		)
		(fp_line
			(start -2.1844 -0.0508)
			(end -2.7178 0.508)
			(stroke
				(width 0.1524)
				(type default)
			)
			(layer "F.SilkS")
		)
		(fp_line
			(start 2.1336 -1.4224)
			(end -2.7432 -1.4224)
			(stroke
				(width 0.1524)
				(type default)
			)
			(layer "F.SilkS")
		)
		(fp_line
			(start 2.1336 1.4224)
			(end 2.1336 -1.4224)
			(stroke
				(width 0.1524)
				(type default)
			)
			(layer "F.SilkS")
		)
		(fp_poly
			(pts
				(xy -2.2098 -1.4224) (xy -2.2098 1.4224) (xy 2.2098 1.4224) (xy 2.2098 -1.4224)
			)
			(stroke
				(width 0)
				(type default)
			)
			(fill yes)
			(layer "F.SilkS")
		)
		(fp_rect
			(start -2.450084 2.999994)
			(end 2.450084 -2.999994)
			(stroke
				(width 0)
				(type default)
			)
			(fill no)
			(layer "F.CrtYd")
		)
		(fp_poly
			(pts
				(xy -2.8194 3.6322) (xy -2.8194 -3.6322) (xy 2.8194 -3.6322) (xy 2.8194 1.18364) (xy 2.450084 1.18364)
				(xy 2.450084 -2.999994) (xy -2.450084 -2.999994) (xy -2.450084 2.999994) (xy 2.450084 2.999994)
				(xy 2.450084 1.18618) (xy 2.8194 1.18618) (xy 2.8194 3.6322)
			)
			(stroke
				(width 0)
				(type default)
			)
			(fill no)
			(layer "F.CrtYd")
		)
		(fp_rect
			(start -2.8194 3.6322)
			(end 2.8194 -3.6322)
			(stroke
				(width 0)
				(type default)
			)
			(fill no)
			(layer "F.Fab")
		)
		(pad "1" smd rect
			(at -1.905 2.54)
			(size 0.635 1.651)
			(layers "F.Cu" "F.Mask" "F.Paste")
			(net "P12V_A")
		)
		(pad "2" smd rect
			(at -0.635 2.54)
			(size 0.635 1.651)
			(layers "F.Cu" "F.Mask" "F.Paste")
			(net "P12V_A")
		)
		(pad "3" smd rect
			(at 0.635 2.54)
			(size 0.635 1.651)
			(layers "F.Cu" "F.Mask" "F.Paste")
			(net "P12V_A")
		)
		(pad "4" smd rect
			(at 1.905 2.54)
			(size 0.635 1.651)
			(layers "F.Cu" "F.Mask" "F.Paste")
			(net "SW_HDD_N28")
		)
		(pad "5" smd rect
			(at 1.905 -2.54)
			(size 0.635 1.651)
			(layers "F.Cu" "F.Mask" "F.Paste")
			(net "P12V_HDD28")
		)
		(pad "6" smd rect
			(at 0.635 -2.54)
			(size 0.635 1.651)
			(layers "F.Cu" "F.Mask" "F.Paste")
			(net "P12V_HDD28")
		)
		(pad "7" smd rect
			(at -0.635 -2.54)
			(size 0.635 1.651)
			(layers "F.Cu" "F.Mask" "F.Paste")
			(net "P12V_HDD28")
		)
		(pad "8" smd rect
			(at -1.905 -2.54)
			(size 0.635 1.651)
			(layers "F.Cu" "F.Mask" "F.Paste")
			(net "P12V_HDD28")
		)
	)
	(footprint ""
		(layer "F.Cu")
		(at 300.689772 -184.5945 90)
		(property "Reference" "C121"
			(at 0 0 90)
			(layer "F.SilkS")
			(hide yes)
			(effects
				(font
					(size 1.27 1.27)
				)
			)
		)
		(property "Value" "SC22U25V6KX-2-GP-U"
			(at -2.860802 -5.279644 90)
			(unlocked yes)
			(layer "F.Fab")
			(hide yes)
			(effects
				(font
					(size 1.016 1.016)
					(thickness 0.1524)
				)
			)
		)
		(property "Device Type" "C1206-TO0D3H75"
			(at -2.860802 -6.803644 90)
			(unlocked yes)
			(layer "F.Fab")
			(hide yes)
			(effects
				(font
					(size 1.016 1.016)
					(thickness 0.1524)
				)
			)
		)
		(duplicate_pad_numbers_are_jumpers no)
		(fp_line
			(start 1.3081 -2.3749)
			(end 1.3081 2.3749)
			(stroke
				(width 0.1524)
				(type default)
			)
			(layer "F.SilkS")
		)
		(fp_line
			(start -1.3081 -2.3749)
			(end 1.3081 -2.3749)
			(stroke
				(width 0.1524)
				(type default)
			)
			(layer "F.SilkS")
		)
		(fp_line
			(start 1.3081 2.3749)
			(end -1.3081 2.3749)
			(stroke
				(width 0.1524)
				(type default)
			)
			(layer "F.SilkS")
		)
		(fp_line
			(start -1.3081 2.3749)
			(end -1.3081 -2.3749)
			(stroke
				(width 0.1524)
				(type default)
			)
			(layer "F.SilkS")
		)
		(fp_rect
			(start -0.8001 1.6002)
			(end 0.8001 -1.6002)
			(stroke
				(width 0)
				(type default)
			)
			(fill no)
			(layer "F.CrtYd")
		)
		(fp_poly
			(pts
				(xy -1.5621 2.4511) (xy -1.5621 1.6002) (xy 0.8001 1.6002) (xy 0.8001 -1.6002) (xy -0.8001 -1.6002)
				(xy -0.8001 1.5875) (xy -1.5621 1.5875) (xy -1.5621 -2.4511) (xy 1.5621 -2.4511) (xy 1.5621 2.4511)
			)
			(stroke
				(width 0)
				(type default)
			)
			(fill no)
			(layer "F.CrtYd")
		)
		(fp_rect
			(start -1.5621 2.4511)
			(end 1.5621 -2.4511)
			(stroke
				(width 0)
				(type default)
			)
			(fill no)
			(layer "F.Fab")
		)
		(pad "1" smd rect
			(at 0 -1.392936 90)
			(size 2.1082 1.4478)
			(layers "F.Cu" "F.Mask" "F.Paste")
			(net "P12V_B_COMP")
		)
		(pad "2" smd rect
			(at 0 1.392936 90)
			(size 2.1082 1.4478)
			(layers "F.Cu" "F.Mask" "F.Paste")
			(net "GND")
		)
	)
	(footprint ""
		(layer "F.Cu")
		(at 318.262 -291.127942 -90)
		(property "Reference" "C124"
			(at 0 0 270)
			(layer "F.SilkS")
			(hide yes)
			(effects
				(font
					(size 1.27 1.27)
				)
			)
		)
		(property "Value" "SCD01U50V2KX-1GP"
			(at 1.1811 -2.7051 270)
			(unlocked yes)
			(layer "F.Fab")
			(hide yes)
			(effects
				(font
					(size 1.016 1.016)
					(thickness 0.1524)
				)
			)
		)
		(property "Device Type" "C402H22"
			(at 1.1811 -4.2291 270)
			(unlocked yes)
			(layer "F.Fab")
			(hide yes)
			(effects
				(font
					(size 1.016 1.016)
					(thickness 0.1524)
				)
			)
		)
		(duplicate_pad_numbers_are_jumpers no)
		(fp_rect
			(start -0.4318 0.9525)
			(end 0.4318 -0.9525)
			(stroke
				(width 0)
				(type default)
			)
			(fill no)
			(layer "F.CrtYd")
		)
		(fp_rect
			(start -0.4318 0.9525)
			(end 0.4318 -0.9525)
			(stroke
				(width 0)
				(type default)
			)
			(fill no)
			(layer "F.Fab")
		)
		(pad "1" smd custom
			(at 0 -0.4445 270)
			(size 0.1524 0.1524)
			(layers "F.Cu" "F.Mask" "F.Paste")
			(net "HDD_PRSNT_6")
			(options
				(clearance outline)
				(anchor circle)
			)
			(primitives
				(gr_poly
					(pts
						(arc
							(start 0.3048 -0.2032)
							(mid 0.275042 -0.275042)
							(end 0.2032 -0.3048)
						)
						(arc
							(start -0.2032 -0.3048)
							(mid -0.275042 -0.275042)
							(end -0.3048 -0.2032)
						)
						(arc
							(start -0.3048 0.2032)
							(mid -0.275042 0.275042)
							(end -0.2032 0.3048)
						)
						(arc
							(start 0.2032 0.3048)
							(mid 0.275042 0.275042)
							(end 0.3048 0.2032)
						)
					)
					(width 0)
					(fill yes)
				)
			)
		)
		(pad "2" smd custom
			(at 0 0.4445 270)
			(size 0.1524 0.1524)
			(layers "F.Cu" "F.Mask" "F.Paste")
			(net "GND")
			(options
				(clearance outline)
				(anchor circle)
			)
			(primitives
				(gr_poly
					(pts
						(arc
							(start 0.3048 -0.2032)
							(mid 0.275042 -0.275042)
							(end 0.2032 -0.3048)
						)
						(arc
							(start -0.2032 -0.3048)
							(mid -0.275042 -0.275042)
							(end -0.3048 -0.2032)
						)
						(arc
							(start -0.3048 0.2032)
							(mid -0.275042 0.275042)
							(end -0.2032 0.3048)
						)
						(arc
							(start 0.2032 0.3048)
							(mid 0.275042 0.275042)
							(end 0.3048 0.2032)
						)
					)
					(width 0)
					(fill yes)
				)
			)
		)
	)
	(footprint ""
		(layer "F.Cu")
		(at 315.484256 -290.934902 90)
		(property "Reference" "R576"
			(at 0 0 90)
			(layer "F.SilkS")
			(hide yes)
			(effects
				(font
					(size 1.27 1.27)
				)
			)
		)
		(property "Value" "4K7R2J-2-GP"
			(at 0.064008 -3.993896 90)
			(unlocked yes)
			(layer "F.Fab")
			(hide yes)
			(effects
				(font
					(size 1.016 1.016)
					(thickness 0.1524)
				)
			)
		)
		(property "Device Type" "R402H16"
			(at 0.064008 -5.517896 90)
			(unlocked yes)
			(layer "F.Fab")
			(hide yes)
			(effects
				(font
					(size 1.016 1.016)
					(thickness 0.1524)
				)
			)
		)
		(duplicate_pad_numbers_are_jumpers no)
		(fp_line
			(start 0.508 -0.9398)
			(end -0.508 -0.9398)
			(stroke
				(width 0.1524)
				(type default)
			)
			(layer "F.SilkS")
		)
		(fp_line
			(start -0.508 -0.9398)
			(end -0.508 0.9398)
			(stroke
				(width 0.1524)
				(type default)
			)
			(layer "F.SilkS")
		)
		(fp_rect
			(start -0.508 0.9398)
			(end 0.508 -0.9398)
			(stroke
				(width 0)
				(type default)
			)
			(fill no)
			(layer "F.CrtYd")
		)
		(fp_rect
			(start -0.508 0.9398)
			(end 0.508 -0.9398)
			(stroke
				(width 0)
				(type default)
			)
			(fill no)
			(layer "F.Fab")
		)
		(pad "1" smd custom
			(at 0 -0.4445 90)
			(size 0.1397 0.1397)
			(layers "F.Cu" "F.Mask" "F.Paste")
			(net "DRIVE_B_30_ACT")
			(options
				(clearance outline)
				(anchor circle)
			)
			(primitives
				(gr_poly
					(pts
						(arc
							(start -0.1778 -0.2794)
							(mid -0.249642 -0.249642)
							(end -0.2794 -0.1778)
						)
						(arc
							(start -0.2794 0.1778)
							(mid -0.249642 0.249642)
							(end -0.1778 0.2794)
						)
						(arc
							(start 0.1778 0.2794)
							(mid 0.249642 0.249642)
							(end 0.2794 0.1778)
						)
						(arc
							(start 0.2794 -0.1778)
							(mid 0.249642 -0.249642)
							(end 0.1778 -0.2794)
						)
					)
					(width 0)
					(fill yes)
				)
			)
		)
		(pad "2" smd custom
			(at 0 0.4445 90)
			(size 0.1397 0.1397)
			(layers "F.Cu" "F.Mask" "F.Paste")
			(net "GND")
			(options
				(clearance outline)
				(anchor circle)
			)
			(primitives
				(gr_poly
					(pts
						(arc
							(start -0.1778 -0.2794)
							(mid -0.249642 -0.249642)
							(end -0.2794 -0.1778)
						)
						(arc
							(start -0.2794 0.1778)
							(mid -0.249642 0.249642)
							(end -0.1778 0.2794)
						)
						(arc
							(start 0.1778 0.2794)
							(mid 0.249642 0.249642)
							(end 0.2794 0.1778)
						)
						(arc
							(start 0.2794 -0.1778)
							(mid 0.249642 -0.249642)
							(end 0.1778 -0.2794)
						)
					)
					(width 0)
					(fill yes)
				)
			)
		)
	)
	(footprint ""
		(layer "F.Cu")
		(at 190.246 -183.747918)
		(property "Reference" "TP87"
			(at 0 0 0)
			(layer "F.SilkS")
			(hide yes)
			(effects
				(font
					(size 1.27 1.27)
				)
			)
		)
		(property "Value" "TPAD32-GP"
			(at -0.0508 -1.6764 0)
			(unlocked yes)
			(layer "F.Fab")
			(hide yes)
			(effects
				(font
					(size 1.016 1.016)
					(thickness 0.1524)
				)
			)
		)
		(property "Device Type" "TPAD32"
			(at -0.0508 -3.2004 0)
			(unlocked yes)
			(layer "F.Fab")
			(hide yes)
			(effects
				(font
					(size 1.016 1.016)
					(thickness 0.1524)
				)
			)
		)
		(duplicate_pad_numbers_are_jumpers no)
		(fp_poly
			(pts
				(arc
					(start 0.4064 0)
					(mid -0.4064 0)
					(end 0.4064 0)
				)
			)
			(stroke
				(width 0)
				(type default)
			)
			(fill no)
			(layer "F.CrtYd")
		)
		(fp_poly
			(pts
				(arc
					(start 0.7112 0)
					(mid -0.7112 0)
					(end 0.7112 0)
				)
			)
			(stroke
				(width 0)
				(type default)
			)
			(fill no)
			(layer "F.Fab")
		)
		(pad "1" smd circle
			(at 0 0)
			(size 0.8128 0.8128)
			(layers "F.Cu" "F.Mask" "F.Paste")
			(net "ACT_HDD_17")
		)
	)
	(footprint ""
		(layer "F.Cu")
		(at 223.347534 -377.002294 180)
		(property "Reference" "R156"
			(at 0 0 180)
			(layer "F.SilkS")
			(hide yes)
			(effects
				(font
					(size 1.27 1.27)
				)
			)
		)
		(property "Value" "0R2J-2-GP"
			(at 0.064008 -3.993896 180)
			(unlocked yes)
			(layer "F.Fab")
			(hide yes)
			(effects
				(font
					(size 1.016 1.016)
					(thickness 0.1524)
				)
			)
		)
		(property "Device Type" "R402H16"
			(at 0.064008 -5.517896 180)
			(unlocked yes)
			(layer "F.Fab")
			(hide yes)
			(effects
				(font
					(size 1.016 1.016)
					(thickness 0.1524)
				)
			)
		)
		(duplicate_pad_numbers_are_jumpers no)
		(fp_line
			(start 0.508 -0.9398)
			(end -0.508 -0.9398)
			(stroke
				(width 0.1524)
				(type default)
			)
			(layer "F.SilkS")
		)
		(fp_line
			(start -0.508 -0.9398)
			(end -0.508 0.9398)
			(stroke
				(width 0.1524)
				(type default)
			)
			(layer "F.SilkS")
		)
		(fp_rect
			(start -0.508 0.9398)
			(end 0.508 -0.9398)
			(stroke
				(width 0)
				(type default)
			)
			(fill no)
			(layer "F.CrtYd")
		)
		(fp_rect
			(start -0.508 0.9398)
			(end 0.508 -0.9398)
			(stroke
				(width 0)
				(type default)
			)
			(fill no)
			(layer "F.Fab")
		)
		(pad "1" smd custom
			(at 0 -0.4445 180)
			(size 0.1397 0.1397)
			(layers "F.Cu" "F.Mask" "F.Paste")
			(net "IO_EXP3_LED_SDA")
			(options
				(clearance outline)
				(anchor circle)
			)
			(primitives
				(gr_poly
					(pts
						(arc
							(start -0.1778 -0.2794)
							(mid -0.249642 -0.249642)
							(end -0.2794 -0.1778)
						)
						(arc
							(start -0.2794 0.1778)
							(mid -0.249642 0.249642)
							(end -0.1778 0.2794)
						)
						(arc
							(start 0.1778 0.2794)
							(mid 0.249642 0.249642)
							(end 0.2794 0.1778)
						)
						(arc
							(start 0.2794 -0.1778)
							(mid 0.249642 -0.249642)
							(end 0.1778 -0.2794)
						)
					)
					(width 0)
					(fill yes)
				)
			)
		)
		(pad "2" smd custom
			(at 0 0.4445 180)
			(size 0.1397 0.1397)
			(layers "F.Cu" "F.Mask" "F.Paste")
			(net "I2C_DRIVE_B_FLT_LED_SDA")
			(options
				(clearance outline)
				(anchor circle)
			)
			(primitives
				(gr_poly
					(pts
						(arc
							(start -0.1778 -0.2794)
							(mid -0.249642 -0.249642)
							(end -0.2794 -0.1778)
						)
						(arc
							(start -0.2794 0.1778)
							(mid -0.249642 0.249642)
							(end -0.1778 0.2794)
						)
						(arc
							(start 0.1778 0.2794)
							(mid 0.249642 0.249642)
							(end 0.2794 0.1778)
						)
						(arc
							(start 0.2794 -0.1778)
							(mid 0.249642 -0.249642)
							(end 0.1778 -0.2794)
						)
					)
					(width 0)
					(fill yes)
				)
			)
		)
	)
)
